# S9S_MB_2U (Grand Teton) — schematic netlist excerpt (pin names and nets, part order shuffled) for the footprints in the layout excerpt that follows; sources: Cadence DE-HDL packaged netlist, KiCad conversion of 03242023_DA0F0TMBIJ0_F0T_Motherboard_J_brd_V01_OCP.brd

PR3915  Q_RES  2K 0.1% CHIP  pkg 0402LF  page 302 : A = HSC_CS_2 ; B = AGND_HSC
R4409  Q_RES  1.5K 1% CHIP  pkg 0402LF  page 123 : A = H_CPU0_MEMTRIP ; B = H_CPU0_MEMTRIP_R

(kicad_pcb
	(version 20260206)
	(generator "pcbnew")
	(generator_version "10.0")
	(general
		(thickness 1.6)
		(legacy_teardrops no)
	)
	(paper "A4")
	(title_block
		(title "03242023_DA0F0TMBIJ0_F0T_Motherboard_J_brd_V01_OCP.brd")
		(comment 1 "Grand Teton / footprints 3955-3956 of 6105")
	)
	(layers
		(0 "F.Cu" signal "TOP")
		(4 "In1.Cu" signal "GND")
		(6 "In2.Cu" signal "IN1")
		(8 "In3.Cu" signal "GND1")
		(10 "In4.Cu" signal "IN2")
		(12 "In5.Cu" signal "GND2")
		(14 "In6.Cu" signal "IN3")
		(16 "In7.Cu" signal "GND3")
		(18 "In8.Cu" signal "VCC")
		(20 "In9.Cu" signal "VCC1")
		(22 "In10.Cu" signal "GND4")
		(24 "In11.Cu" signal "IN4")
		(26 "In12.Cu" signal "GND5")
		(28 "In13.Cu" signal "IN5")
		(30 "In14.Cu" signal "GND6")
		(32 "In15.Cu" signal "IN6")
		(34 "In16.Cu" signal "GND7")
		(2 "B.Cu" signal "BOTTOM")
		(9 "F.Adhes" user "F.Adhesive")
		(11 "B.Adhes" user "B.Adhesive")
		(13 "F.Paste" user "Package Geometry/Pastemask Top")
		(15 "B.Paste" user "Package Geometry/Pastemask Bottom")
		(5 "F.SilkS" user "Ref Des/Silkscreen Top")
		(7 "B.SilkS" user "Ref Des/Silkscreen Bottom")
		(1 "F.Mask" user "Board Geometry/Soldermask Top")
		(3 "B.Mask" user "Board Geometry/Soldermask Bottom")
		(17 "Dwgs.User" user "User.Drawings")
		(19 "Cmts.User" user "User.Comments")
		(21 "Eco1.User" user "User.Eco1")
		(23 "Eco2.User" user "User.Eco2")
		(25 "Edge.Cuts" user "Board Geometry/Outline")
		(27 "Margin" user)
		(31 "F.CrtYd" user "Package Geometry/Place Bound Top")
		(29 "B.CrtYd" user "Package Geometry/Place Bound Bottom")
		(35 "F.Fab" user "Ref Des/Assembly Top")
		(33 "B.Fab" user "Ref Des/Assembly Bottom")
	)
	(footprint ""
		(layer "F.Cu")
		(at 129.46888 -106.898948)
		(property "Reference" "R4409"
			(at 0 0 0)
			(layer "F.SilkS")
			(hide yes)
			(effects
				(font
					(size 1.27 1.27)
				)
			)
		)
		(property "Value" ""
			(at 0 0 0)
			(layer "F.Fab")
			(effects
				(font
					(size 1.27 1.27)
				)
			)
		)
		(duplicate_pad_numbers_are_jumpers no)
		(fp_line
			(start -0.7874 -0.4064)
			(end 0.7874 -0.4064)
			(stroke
				(width 0.1524)
				(type default)
			)
			(layer "F.SilkS")
		)
		(fp_line
			(start -0.7874 0.4064)
			(end -0.7874 -0.4064)
			(stroke
				(width 0.1524)
				(type default)
			)
			(layer "F.SilkS")
		)
		(fp_line
			(start 0.7874 -0.4064)
			(end 0.7874 0.4064)
			(stroke
				(width 0.1524)
				(type default)
			)
			(layer "F.SilkS")
		)
		(fp_line
			(start 0.7874 0.4064)
			(end -0.7874 0.4064)
			(stroke
				(width 0.1524)
				(type default)
			)
			(layer "F.SilkS")
		)
		(fp_line
			(start -0.67945 -0.305054)
			(end -0.12065 -0.305054)
			(stroke
				(width 0.1)
				(type default)
			)
			(layer "F.Fab")
		)
		(fp_line
			(start -0.67945 0.3048)
			(end -0.67945 -0.305054)
			(stroke
				(width 0.1)
				(type default)
			)
			(layer "F.Fab")
		)
		(fp_line
			(start -0.12065 -0.305054)
			(end -0.12065 -0.2794)
			(stroke
				(width 0.1)
				(type default)
			)
			(layer "F.Fab")
		)
		(fp_line
			(start -0.12065 -0.2794)
			(end 0.12065 -0.2794)
			(stroke
				(width 0.1)
				(type default)
			)
			(layer "F.Fab")
		)
		(fp_line
			(start -0.12065 0.2794)
			(end -0.12065 0.3048)
			(stroke
				(width 0.1)
				(type default)
			)
			(layer "F.Fab")
		)
		(fp_line
			(start -0.12065 0.3048)
			(end -0.67945 0.3048)
			(stroke
				(width 0.1)
				(type default)
			)
			(layer "F.Fab")
		)
		(fp_line
			(start 0.120396 0.2794)
			(end -0.12065 0.2794)
			(stroke
				(width 0.1)
				(type default)
			)
			(layer "F.Fab")
		)
		(fp_line
			(start 0.120396 0.3048)
			(end 0.120396 0.2794)
			(stroke
				(width 0.1)
				(type default)
			)
			(layer "F.Fab")
		)
		(fp_line
			(start 0.12065 -0.3048)
			(end 0.67945 -0.3048)
			(stroke
				(width 0.1)
				(type default)
			)
			(layer "F.Fab")
		)
		(fp_line
			(start 0.12065 -0.2794)
			(end 0.12065 -0.3048)
			(stroke
				(width 0.1)
				(type default)
			)
			(layer "F.Fab")
		)
		(fp_line
			(start 0.67945 -0.3048)
			(end 0.67945 0.3048)
			(stroke
				(width 0.1)
				(type default)
			)
			(layer "F.Fab")
		)
		(fp_line
			(start 0.67945 0.3048)
			(end 0.120396 0.3048)
			(stroke
				(width 0.1)
				(type default)
			)
			(layer "F.Fab")
		)
		(pad "1" smd circle
			(at -0.40005 0)
			(size 0 0)
			(layers "F.Cu" "F.Mask" "F.Paste")
			(net "H_CPU0_MEMTRIP")
		)
		(pad "2" smd circle
			(at 0.40005 0)
			(size 0 0)
			(layers "F.Cu" "F.Mask" "F.Paste")
			(net "H_CPU0_MEMTRIP_R")
		)
	)
	(footprint ""
		(layer "F.Cu")
		(at 205.397608 -401.775422 180)
		(property "Reference" "PR3915"
			(at 0 0 180)
			(layer "F.SilkS")
			(hide yes)
			(effects
				(font
					(size 1.27 1.27)
				)
			)
		)
		(property "Value" ""
			(at 0 0 180)
			(layer "F.Fab")
			(effects
				(font
					(size 1.27 1.27)
				)
			)
		)
		(duplicate_pad_numbers_are_jumpers no)
		(fp_line
			(start 0.7874 0.4064)
			(end -0.7874 0.4064)
			(stroke
				(width 0.1524)
				(type default)
			)
			(layer "F.SilkS")
		)
		(fp_line
			(start 0.7874 -0.4064)
			(end 0.7874 0.4064)
			(stroke
				(width 0.1524)
				(type default)
			)
			(layer "F.SilkS")
		)
		(fp_line
			(start -0.7874 0.4064)
			(end -0.7874 -0.4064)
			(stroke
				(width 0.1524)
				(type default)
			)
			(layer "F.SilkS")
		)
		(fp_line
			(start -0.7874 -0.4064)
			(end 0.7874 -0.4064)
			(stroke
				(width 0.1524)
				(type default)
			)
			(layer "F.SilkS")
		)
		(fp_line
			(start 0.67945 0.3048)
			(end 0.120396 0.3048)
			(stroke
				(width 0.1)
				(type default)
			)
			(layer "F.Fab")
		)
		(fp_line
			(start 0.67945 -0.3048)
			(end 0.67945 0.3048)
			(stroke
				(width 0.1)
				(type default)
			)
			(layer "F.Fab")
		)
		(fp_line
			(start 0.12065 -0.2794)
			(end 0.12065 -0.3048)
			(stroke
				(width 0.1)
				(type default)
			)
			(layer "F.Fab")
		)
		(fp_line
			(start 0.12065 -0.3048)
			(end 0.67945 -0.3048)
			(stroke
				(width 0.1)
				(type default)
			)
			(layer "F.Fab")
		)
		(fp_line
			(start 0.120396 0.3048)
			(end 0.120396 0.2794)
			(stroke
				(width 0.1)
				(type default)
			)
			(layer "F.Fab")
		)
		(fp_line
			(start 0.120396 0.2794)
			(end -0.12065 0.2794)
			(stroke
				(width 0.1)
				(type default)
			)
			(layer "F.Fab")
		)
		(fp_line
			(start -0.12065 0.3048)
			(end -0.67945 0.3048)
			(stroke
				(width 0.1)
				(type default)
			)
			(layer "F.Fab")
		)
		(fp_line
			(start -0.12065 0.2794)
			(end -0.12065 0.3048)
			(stroke
				(width 0.1)
				(type default)
			)
			(layer "F.Fab")
		)
		(fp_line
			(start -0.12065 -0.2794)
			(end 0.12065 -0.2794)
			(stroke
				(width 0.1)
				(type default)
			)
			(layer "F.Fab")
		)
		(fp_line
			(start -0.12065 -0.305054)
			(end -0.12065 -0.2794)
			(stroke
				(width 0.1)
				(type default)
			)
			(layer "F.Fab")
		)
		(fp_line
			(start -0.67945 0.3048)
			(end -0.67945 -0.305054)
			(stroke
				(width 0.1)
				(type default)
			)
			(layer "F.Fab")
		)
		(fp_line
			(start -0.67945 -0.305054)
			(end -0.12065 -0.305054)
			(stroke
				(width 0.1)
				(type default)
			)
			(layer "F.Fab")
		)
		(pad "1" smd circle
			(at -0.40005 0 180)
			(size 0 0)
			(layers "F.Cu" "F.Mask" "F.Paste")
			(net "HSC_CS_2")
		)
		(pad "2" smd circle
			(at 0.40005 0 180)
			(size 0 0)
			(layers "F.Cu" "F.Mask" "F.Paste")
			(net "AGND_HSC")
		)
	)
)
